# T6G (Grand Teton) — schematic netlist excerpt (pin names and nets, part order shuffled) for the footprints in the layout excerpt that follows; sources: Cadence DE-HDL packaged netlist, KiCad conversion of 04192023_DAF0TMB3IC0_F0TG_MB_C_brd_V02_OCP.brd

X9010  TP_TDR_4P_FTS  TP_TDR_4P_DIP EMPTY  pkg TH  page 261
  S1  = TDR_DIFF_85_NECK_IN3_DN
  P1  = T1_GND
  P2  = T1_GND
  S2  = TDR_DIFF_85_NECK_IN3_DP

C6086  Q_CAP  0.1UF 25V 10% X7R  pkg 0402  page 271 : A = HSC_TYPE_ADC ; B = GND

(kicad_pcb
	(version 20260206)
	(generator "pcbnew")
	(generator_version "10.0")
	(general
		(thickness 1.6)
		(legacy_teardrops no)
	)
	(paper "A4")
	(title_block
		(title "04192023_DAF0TMB3IC0_F0TG_MB_C_brd_V02_OCP.brd")
		(comment 1 "Grand Teton / footprints 639-640 of 8354")
	)
	(layers
		(0 "F.Cu" signal "TOP")
		(4 "In1.Cu" signal "GND")
		(6 "In2.Cu" signal "IN1")
		(8 "In3.Cu" signal "GND1")
		(10 "In4.Cu" signal "IN2")
		(12 "In5.Cu" signal "GND2")
		(14 "In6.Cu" signal "IN3")
		(16 "In7.Cu" signal "GND3")
		(18 "In8.Cu" signal "VCC")
		(20 "In9.Cu" signal "VCC1")
		(22 "In10.Cu" signal "GND4")
		(24 "In11.Cu" signal "IN4")
		(26 "In12.Cu" signal "GND5")
		(28 "In13.Cu" signal "IN5")
		(30 "In14.Cu" signal "GND6")
		(32 "In15.Cu" signal "IN6")
		(34 "In16.Cu" signal "GND7")
		(2 "B.Cu" signal "BOTTOM")
		(9 "F.Adhes" user "F.Adhesive")
		(11 "B.Adhes" user "B.Adhesive")
		(13 "F.Paste" user "Package Geometry/Pastemask Top")
		(15 "B.Paste" user "Package Geometry/Pastemask Bottom")
		(5 "F.SilkS" user "Ref Des/Silkscreen Top")
		(7 "B.SilkS" user "Ref Des/Silkscreen Bottom")
		(1 "F.Mask" user "Board Geometry/Soldermask Top")
		(3 "B.Mask" user "Board Geometry/Soldermask Bottom")
		(17 "Dwgs.User" user "User.Drawings")
		(19 "Cmts.User" user "User.Comments")
		(21 "Eco1.User" user "User.Eco1")
		(23 "Eco2.User" user "User.Eco2")
		(25 "Edge.Cuts" user "Board Geometry/Outline")
		(27 "Margin" user)
		(31 "F.CrtYd" user "Package Geometry/Place Bound Top")
		(29 "B.CrtYd" user "Package Geometry/Place Bound Bottom")
		(35 "F.Fab" user "Ref Des/Assembly Top")
		(33 "B.Fab" user "Ref Des/Assembly Bottom")
	)
	(footprint ""
		(layer "F.Cu")
		(at 484.834946 -306.882292 -90)
		(property "Reference" "X9010"
			(at -1.79451 4.909312 0)
			(unlocked yes)
			(layer "F.SilkS")
			(effects
				(font
					(size 0.7874 0.5842)
					(thickness 0.1524)
				)
				(justify left)
			)
		)
		(property "Value" ""
			(at 0 0 270)
			(layer "F.Fab")
			(effects
				(font
					(size 1.27 1.27)
				)
			)
		)
		(property "User Part Number" "N_A"
			(at 1.30175 1.27 0)
			(unlocked yes)
			(layer "Cmts.User")
			(hide yes)
			(effects
				(font
					(size 0.635 0.4064)
					(thickness 0.1524)
				)
			)
		)
		(property "Device Type" "TP_TDR_4P_FTS_TH-TP_TDR_4P_DIP,EMPTY,TP15"
			(at 1.30175 1.27 0)
			(unlocked yes)
			(layer "F.Fab")
			(hide yes)
			(effects
				(font
					(size 0.635 0.4064)
					(thickness 0.1524)
				)
			)
		)
		(duplicate_pad_numbers_are_jumpers no)
		(fp_line
			(start 0 3.81)
			(end 2.54 3.81)
			(stroke
				(width 0.1524)
				(type default)
			)
			(layer "F.SilkS")
		)
		(fp_line
			(start 2.54 3.81)
			(end 2.54 3.6703)
			(stroke
				(width 0.1524)
				(type default)
			)
			(layer "F.SilkS")
		)
		(fp_line
			(start 0 3.175)
			(end 0 3.81)
			(stroke
				(width 0.1524)
				(type default)
			)
			(layer "F.SilkS")
		)
		(fp_line
			(start 2.54 1.4097)
			(end 2.54 1.1303)
			(stroke
				(width 0.1524)
				(type default)
			)
			(layer "F.SilkS")
		)
		(fp_line
			(start 0 0.635)
			(end 0 1.905)
			(stroke
				(width 0.1524)
				(type default)
			)
			(layer "F.SilkS")
		)
		(fp_line
			(start 2.54 -1.1303)
			(end 2.54 -1.27)
			(stroke
				(width 0.1524)
				(type default)
			)
			(layer "F.SilkS")
		)
		(fp_line
			(start 0 -1.27)
			(end 0 -0.635)
			(stroke
				(width 0.1524)
				(type default)
			)
			(layer "F.SilkS")
		)
		(fp_line
			(start 2.54 -1.27)
			(end 0 -1.27)
			(stroke
				(width 0.1524)
				(type default)
			)
			(layer "F.SilkS")
		)
		(fp_poly
			(pts
				(xy -2.285746 -0.762) (xy -0.761746 0) (xy -2.285746 0.762)
			)
			(stroke
				(width 0)
				(type default)
			)
			(fill yes)
			(layer "F.SilkS")
		)
		(fp_line
			(start 0 3.81)
			(end 2.54 3.81)
			(stroke
				(width 0.1)
				(type default)
			)
			(layer "F.Fab")
		)
		(fp_line
			(start 2.54 3.81)
			(end 2.54 -1.27)
			(stroke
				(width 0.1)
				(type default)
			)
			(layer "F.Fab")
		)
		(fp_line
			(start 0 -1.27)
			(end 0 3.81)
			(stroke
				(width 0.1)
				(type default)
			)
			(layer "F.Fab")
		)
		(fp_line
			(start 2.54 -1.27)
			(end 0 -1.27)
			(stroke
				(width 0.1)
				(type default)
			)
			(layer "F.Fab")
		)
		(fp_poly
			(pts
				(xy -0.761746 0) (xy -2.285746 -0.762) (xy -2.285746 0.762)
			)
			(stroke
				(width 0)
				(type default)
			)
			(fill yes)
			(layer "F.Fab")
		)
		(pad "1" thru_hole circle
			(at 0 0 270)
			(size 1.0033 1.0033)
			(drill 0.249936)
			(layers "*.Cu" "*.Mask")
			(remove_unused_layers no)
			(net "TDR_DIFF_85_NECK_IN3_DN")
			(clearance 0.10795)
			(thermal_gap 0.10795)
			(padstack
				(mode front_inner_back)
				(layer "Inner"
					(shape circle)
					(size 0.8001 0.8001)
					(clearance 0.1524)
				)
				(layer "B.Cu"
					(shape circle)
					(size 1.0033 1.0033)
					(clearance 0.10795)
				)
			)
		)
		(pad "2" thru_hole circle
			(at 2.54 0 270)
			(size 1.9939 1.9939)
			(drill 0.249936)
			(layers "*.Cu" "*.Mask")
			(remove_unused_layers no)
			(net "T1_GND")
			(clearance 0.10795)
			(thermal_gap 0.10795)
			(padstack
				(mode front_inner_back)
				(layer "Inner"
					(shape circle)
					(size 0.8001 0.8001)
					(clearance 0.1524)
				)
				(layer "B.Cu"
					(shape circle)
					(size 1.9939 1.9939)
					(clearance 0.10795)
				)
			)
		)
		(pad "3" thru_hole circle
			(at 2.54 2.54 270)
			(size 1.9939 1.9939)
			(drill 0.249936)
			(layers "*.Cu" "*.Mask")
			(remove_unused_layers no)
			(net "T1_GND")
			(clearance 0.10795)
			(thermal_gap 0.10795)
			(padstack
				(mode front_inner_back)
				(layer "Inner"
					(shape circle)
					(size 0.8001 0.8001)
					(clearance 0.1524)
				)
				(layer "B.Cu"
					(shape circle)
					(size 1.9939 1.9939)
					(clearance 0.10795)
				)
			)
		)
		(pad "4" thru_hole circle
			(at 0 2.54 270)
			(size 1.0033 1.0033)
			(drill 0.249936)
			(layers "*.Cu" "*.Mask")
			(remove_unused_layers no)
			(net "TDR_DIFF_85_NECK_IN3_DP")
			(clearance 0.10795)
			(thermal_gap 0.10795)
			(padstack
				(mode front_inner_back)
				(layer "Inner"
					(shape circle)
					(size 0.8001 0.8001)
					(clearance 0.1524)
				)
				(layer "B.Cu"
					(shape circle)
					(size 1.0033 1.0033)
					(clearance 0.10795)
				)
			)
		)
	)
	(footprint ""
		(layer "F.Cu")
		(at 428.322232 -430.892458 180)
		(property "Reference" "C6086"
			(at 0 0 180)
			(layer "F.SilkS")
			(hide yes)
			(effects
				(font
					(size 1.27 1.27)
				)
			)
		)
		(property "Value" ""
			(at 0 0 180)
			(layer "F.Fab")
			(effects
				(font
					(size 1.27 1.27)
				)
			)
		)
		(duplicate_pad_numbers_are_jumpers no)
		(fp_line
			(start 0.7874 0.4064)
			(end -0.7874 0.4064)
			(stroke
				(width 0.1524)
				(type default)
			)
			(layer "F.SilkS")
		)
		(fp_line
			(start 0.7874 -0.4064)
			(end 0.7874 0.4064)
			(stroke
				(width 0.1524)
				(type default)
			)
			(layer "F.SilkS")
		)
		(fp_line
			(start -0.7874 0.4064)
			(end -0.7874 -0.4064)
			(stroke
				(width 0.1524)
				(type default)
			)
			(layer "F.SilkS")
		)
		(fp_line
			(start -0.7874 -0.4064)
			(end 0.7874 -0.4064)
			(stroke
				(width 0.1524)
				(type default)
			)
			(layer "F.SilkS")
		)
		(fp_line
			(start 0.67945 0.3048)
			(end 0.120396 0.3048)
			(stroke
				(width 0.1)
				(type default)
			)
			(layer "F.Fab")
		)
		(fp_line
			(start 0.67945 -0.3048)
			(end 0.67945 0.3048)
			(stroke
				(width 0.1)
				(type default)
			)
			(layer "F.Fab")
		)
		(fp_line
			(start 0.12065 -0.2794)
			(end 0.12065 -0.3048)
			(stroke
				(width 0.1)
				(type default)
			)
			(layer "F.Fab")
		)
		(fp_line
			(start 0.12065 -0.3048)
			(end 0.67945 -0.3048)
			(stroke
				(width 0.1)
				(type default)
			)
			(layer "F.Fab")
		)
		(fp_line
			(start 0.120396 0.3048)
			(end 0.120396 0.2794)
			(stroke
				(width 0.1)
				(type default)
			)
			(layer "F.Fab")
		)
		(fp_line
			(start 0.120396 0.2794)
			(end -0.12065 0.2794)
			(stroke
				(width 0.1)
				(type default)
			)
			(layer "F.Fab")
		)
		(fp_line
			(start -0.12065 0.3048)
			(end -0.67945 0.3048)
			(stroke
				(width 0.1)
				(type default)
			)
			(layer "F.Fab")
		)
		(fp_line
			(start -0.12065 0.2794)
			(end -0.12065 0.3048)
			(stroke
				(width 0.1)
				(type default)
			)
			(layer "F.Fab")
		)
		(fp_line
			(start -0.12065 -0.2794)
			(end 0.12065 -0.2794)
			(stroke
				(width 0.1)
				(type default)
			)
			(layer "F.Fab")
		)
		(fp_line
			(start -0.12065 -0.305054)
			(end -0.12065 -0.2794)
			(stroke
				(width 0.1)
				(type default)
			)
			(layer "F.Fab")
		)
		(fp_line
			(start -0.67945 0.3048)
			(end -0.67945 -0.305054)
			(stroke
				(width 0.1)
				(type default)
			)
			(layer "F.Fab")
		)
		(fp_line
			(start -0.67945 -0.305054)
			(end -0.12065 -0.305054)
			(stroke
				(width 0.1)
				(type default)
			)
			(layer "F.Fab")
		)
		(pad "1" smd circle
			(at -0.40005 0 180)
			(size 0 0)
			(layers "F.Cu" "F.Mask" "F.Paste")
			(net "HSC_TYPE_ADC")
		)
		(pad "2" smd circle
			(at 0.40005 0 180)
			(size 0 0)
			(layers "F.Cu" "F.Mask" "F.Paste")
			(net "GND")
		)
	)
)
